(kicad_pcb
	(version 20260206)
	(generator "pcbnew")
	(generator_version "10.0")
	(general
		(thickness 1.6)
		(legacy_teardrops no)
	)
	(paper "A4")
	(title_block
		(title "Bryce Canyon_R.DPB_16317-1_OCP.brd")
		(comment 1 "Bryce Canyon / footprints 704-711 of 2099")
	)
	(layers
		(0 "F.Cu" signal "TOP")
		(4 "In1.Cu" signal "L2GND")
		(6 "In2.Cu" signal "L3")
		(8 "In3.Cu" signal "L4VCC")
		(10 "In4.Cu" signal "L5VCC")
		(12 "In5.Cu" signal "L6")
		(14 "In6.Cu" signal "L7GND")
		(2 "B.Cu" signal "BOTTOM")
		(9 "F.Adhes" user "F.Adhesive")
		(11 "B.Adhes" user "B.Adhesive")
		(13 "F.Paste" user "Package Geometry/Pastemask Top")
		(15 "B.Paste" user "Package Geometry/Pastemask Bottom")
		(5 "F.SilkS" user "Ref Des/Silkscreen Top")
		(7 "B.SilkS" user "Ref Des/Silkscreen Bottom")
		(1 "F.Mask" user "Board Geometry/Soldermask Top")
		(3 "B.Mask" user "Board Geometry/Soldermask Bottom")
		(17 "Dwgs.User" user "User.Drawings")
		(19 "Cmts.User" user "User.Comments")
		(21 "Eco1.User" user "User.Eco1")
		(23 "Eco2.User" user "User.Eco2")
		(25 "Edge.Cuts" user "Board Geometry/Outline")
		(27 "Margin" user)
		(31 "F.CrtYd" user "Package Geometry/Place Bound Top")
		(29 "B.CrtYd" user "Package Geometry/Place Bound Bottom")
		(35 "F.Fab" user "Ref Des/Assembly Top")
		(33 "B.Fab" user "Ref Des/Assembly Bottom")
	)
	(footprint ""
		(layer "F.Cu")
		(at 160.963864 -269.705074)
		(property "Reference" "TP41"
			(at 0 0 0)
			(layer "F.SilkS")
			(hide yes)
			(effects
				(font
					(size 1.27 1.27)
				)
			)
		)
		(property "Value" "*"
			(at -0.0508 -1.6764 0)
			(unlocked yes)
			(layer "F.Fab")
			(hide yes)
			(effects
				(font
					(size 1.016 1.016)
					(thickness 0.1524)
				)
			)
		)
		(property "Device Type" "TPAD32"
			(at -0.0508 -3.2004 0)
			(unlocked yes)
			(layer "F.Fab")
			(hide yes)
			(effects
				(font
					(size 1.016 1.016)
					(thickness 0.1524)
				)
			)
		)
		(duplicate_pad_numbers_are_jumpers no)
		(fp_poly
			(pts
				(arc
					(start 0.4064 0)
					(mid -0.4064 0)
					(end 0.4064 0)
				)
			)
			(stroke
				(width 0)
				(type default)
			)
			(fill no)
			(layer "F.CrtYd")
		)
		(fp_poly
			(pts
				(arc
					(start 0.7112 0)
					(mid -0.7112 0)
					(end 0.7112 0)
				)
			)
			(stroke
				(width 0)
				(type default)
			)
			(fill no)
			(layer "F.Fab")
		)
		(pad "1" smd circle
			(at 0 0)
			(size 0.8128 0.8128)
			(layers "F.Cu" "F.Mask" "F.Paste")
			(net "ACT_HDD_4")
		)
	)
	(footprint ""
		(layer "F.Cu")
		(at 118.618 -272.288)
		(property "Reference" "C74"
			(at 0 0 0)
			(layer "F.SilkS")
			(hide yes)
			(effects
				(font
					(size 1.27 1.27)
				)
			)
		)
		(property "Value" "SC4D7U25V5KX-1-GP"
			(at -0.0762 -6.1214 0)
			(unlocked yes)
			(layer "F.Fab")
			(hide yes)
			(effects
				(font
					(size 1.016 1.016)
					(thickness 0.1524)
				)
			)
		)
		(property "Device Type" "C805H58"
			(at -0.0762 -8.1534 0)
			(unlocked yes)
			(layer "F.Fab")
			(hide yes)
			(effects
				(font
					(size 1.016 1.016)
					(thickness 0.1524)
				)
			)
		)
		(duplicate_pad_numbers_are_jumpers no)
		(fp_line
			(start 0.635 0)
			(end -0.635 0)
			(stroke
				(width 0.508)
				(type default)
			)
			(layer "F.SilkS")
		)
		(fp_rect
			(start -0.9652 1.778)
			(end 0.9652 -1.778)
			(stroke
				(width 0)
				(type default)
			)
			(fill no)
			(layer "F.CrtYd")
		)
		(fp_poly
			(pts
				(xy -0.9652 -1.778) (xy 0.9652 -1.778) (xy 0.9652 1.778) (xy -0.9652 1.778)
			)
			(stroke
				(width 0)
				(type default)
			)
			(fill no)
			(layer "F.Fab")
		)
		(pad "1" smd rect
			(at 0 -0.9652)
			(size 1.397 1.143)
			(layers "F.Cu" "F.Mask" "F.Paste")
			(net "P12V_HDD3")
		)
		(pad "2" smd rect
			(at 0 0.9652)
			(size 1.397 1.143)
			(layers "F.Cu" "F.Mask" "F.Paste")
			(net "GND")
		)
	)
	(footprint ""
		(layer "F.Cu")
		(at 396.7226 -40.5892 -90)
		(property "Reference" "R807"
			(at 0 0 270)
			(layer "F.SilkS")
			(hide yes)
			(effects
				(font
					(size 1.27 1.27)
				)
			)
		)
		(property "Value" "2R6F-GP"
			(at -0.0508 -4.8514 270)
			(unlocked yes)
			(layer "F.Fab")
			(hide yes)
			(effects
				(font
					(size 1.016 1.016)
					(thickness 0.1524)
				)
			)
		)
		(property "Device Type" "R1206H26"
			(at 0 -6.3754 270)
			(unlocked yes)
			(layer "F.Fab")
			(hide yes)
			(effects
				(font
					(size 1.016 1.016)
					(thickness 0.1524)
				)
			)
		)
		(duplicate_pad_numbers_are_jumpers no)
		(fp_line
			(start -1.016 2.2352)
			(end -1.016 -2.2352)
			(stroke
				(width 0.1524)
				(type default)
			)
			(layer "F.SilkS")
		)
		(fp_line
			(start 1.016 2.2352)
			(end -1.016 2.2352)
			(stroke
				(width 0.1524)
				(type default)
			)
			(layer "F.SilkS")
		)
		(fp_line
			(start -1.016 -2.2352)
			(end 1.016 -2.2352)
			(stroke
				(width 0.1524)
				(type default)
			)
			(layer "F.SilkS")
		)
		(fp_line
			(start 1.016 -2.2352)
			(end 1.016 2.2352)
			(stroke
				(width 0.1524)
				(type default)
			)
			(layer "F.SilkS")
		)
		(fp_rect
			(start -1.0922 2.3114)
			(end 1.0922 -2.3114)
			(stroke
				(width 0)
				(type default)
			)
			(fill no)
			(layer "F.CrtYd")
		)
		(fp_poly
			(pts
				(xy -1.0922 -2.3114) (xy 1.0922 -2.3114) (xy 1.0922 2.3114) (xy -1.0922 2.3114)
			)
			(stroke
				(width 0)
				(type default)
			)
			(fill no)
			(layer "F.Fab")
		)
		(pad "1" smd rect
			(at 0 -1.397 270)
			(size 1.651 1.27)
			(layers "F.Cu" "F.Mask" "F.Paste")
			(net "P12V_HDD32")
		)
		(pad "2" smd rect
			(at 0 1.397 270)
			(size 1.651 1.27)
			(layers "F.Cu" "F.Mask" "F.Paste")
			(net "12V_PRE_32")
		)
	)
	(footprint ""
		(layer "F.Cu")
		(at 158.663386 -14.660626 90)
		(property "Reference" "C393"
			(at 0 0 90)
			(layer "F.SilkS")
			(hide yes)
			(effects
				(font
					(size 1.27 1.27)
				)
			)
		)
		(property "Value" "SCD01U16V1KX-GP"
			(at -2.8321 -1.7399 90)
			(unlocked yes)
			(layer "F.Fab")
			(hide yes)
			(effects
				(font
					(size 1.016 1.016)
					(thickness 0.1524)
				)
			)
		)
		(property "Device Type" "C0201H13"
			(at -2.8321 -3.2639 90)
			(unlocked yes)
			(layer "F.Fab")
			(hide yes)
			(effects
				(font
					(size 1.016 1.016)
					(thickness 0.1524)
				)
			)
		)
		(duplicate_pad_numbers_are_jumpers no)
		(fp_rect
			(start -0.2794 0.6477)
			(end 0.2794 -0.6477)
			(stroke
				(width 0)
				(type default)
			)
			(fill no)
			(layer "F.CrtYd")
		)
		(fp_rect
			(start -0.2794 0.6477)
			(end 0.2794 -0.6477)
			(stroke
				(width 0)
				(type default)
			)
			(fill no)
			(layer "F.Fab")
		)
		(pad "1" smd custom
			(at 0 -0.2794 90)
			(size 0.0762 0.0762)
			(layers "F.Cu" "F.Mask" "F.Paste")
			(net "SAS_HDD_RX_P28")
			(options
				(clearance outline)
				(anchor circle)
			)
			(primitives
				(gr_poly
					(pts
						(arc
							(start 0.1524 -0.127)
							(mid 0.137521 -0.162921)
							(end 0.1016 -0.1778)
						)
						(arc
							(start -0.1016 -0.1778)
							(mid -0.137521 -0.162921)
							(end -0.1524 -0.127)
						)
						(arc
							(start -0.1524 0.127)
							(mid -0.137521 0.162921)
							(end -0.1016 0.1778)
						)
						(arc
							(start 0.1016 0.1778)
							(mid 0.137521 0.162921)
							(end 0.1524 0.127)
						)
					)
					(width 0)
					(fill yes)
				)
			)
		)
		(pad "2" smd custom
			(at 0 0.2794 90)
			(size 0.0762 0.0762)
			(layers "F.Cu" "F.Mask" "F.Paste")
			(net "PHY_SCC_B_TO_DRV_B_28_DP")
			(options
				(clearance outline)
				(anchor circle)
			)
			(primitives
				(gr_poly
					(pts
						(arc
							(start 0.1524 -0.127)
							(mid 0.137521 -0.162921)
							(end 0.1016 -0.1778)
						)
						(arc
							(start -0.1016 -0.1778)
							(mid -0.137521 -0.162921)
							(end -0.1524 -0.127)
						)
						(arc
							(start -0.1524 0.127)
							(mid -0.137521 0.162921)
							(end -0.1016 0.1778)
						)
						(arc
							(start 0.1016 0.1778)
							(mid 0.137521 0.162921)
							(end 0.1524 0.127)
						)
					)
					(width 0)
					(fill yes)
				)
			)
		)
	)
	(footprint ""
		(layer "F.Cu")
		(at 64.013334 -130.21945 90)
		(property "Reference" "C197"
			(at 0 0 90)
			(layer "F.SilkS")
			(hide yes)
			(effects
				(font
					(size 1.27 1.27)
				)
			)
		)
		(property "Value" "SCD01U16V1KX-GP"
			(at -2.8321 -1.7399 90)
			(unlocked yes)
			(layer "F.Fab")
			(hide yes)
			(effects
				(font
					(size 1.016 1.016)
					(thickness 0.1524)
				)
			)
		)
		(property "Device Type" "C0201H13"
			(at -2.8321 -3.2639 90)
			(unlocked yes)
			(layer "F.Fab")
			(hide yes)
			(effects
				(font
					(size 1.016 1.016)
					(thickness 0.1524)
				)
			)
		)
		(duplicate_pad_numbers_are_jumpers no)
		(fp_rect
			(start -0.2794 0.6477)
			(end 0.2794 -0.6477)
			(stroke
				(width 0)
				(type default)
			)
			(fill no)
			(layer "F.CrtYd")
		)
		(fp_rect
			(start -0.2794 0.6477)
			(end 0.2794 -0.6477)
			(stroke
				(width 0)
				(type default)
			)
			(fill no)
			(layer "F.Fab")
		)
		(pad "1" smd custom
			(at 0 -0.2794 90)
			(size 0.0762 0.0762)
			(layers "F.Cu" "F.Mask" "F.Paste")
			(net "SAS_HDD_RX_N13")
			(options
				(clearance outline)
				(anchor circle)
			)
			(primitives
				(gr_poly
					(pts
						(arc
							(start 0.1524 -0.127)
							(mid 0.137521 -0.162921)
							(end 0.1016 -0.1778)
						)
						(arc
							(start -0.1016 -0.1778)
							(mid -0.137521 -0.162921)
							(end -0.1524 -0.127)
						)
						(arc
							(start -0.1524 0.127)
							(mid -0.137521 0.162921)
							(end -0.1016 0.1778)
						)
						(arc
							(start 0.1016 0.1778)
							(mid 0.137521 0.162921)
							(end 0.1524 0.127)
						)
					)
					(width 0)
					(fill yes)
				)
			)
		)
		(pad "2" smd custom
			(at 0 0.2794 90)
			(size 0.0762 0.0762)
			(layers "F.Cu" "F.Mask" "F.Paste")
			(net "PHY_SCC_B_TO_DRV_B_13_DN")
			(options
				(clearance outline)
				(anchor circle)
			)
			(primitives
				(gr_poly
					(pts
						(arc
							(start 0.1524 -0.127)
							(mid 0.137521 -0.162921)
							(end 0.1016 -0.1778)
						)
						(arc
							(start -0.1016 -0.1778)
							(mid -0.137521 -0.162921)
							(end -0.1524 -0.127)
						)
						(arc
							(start -0.1524 0.127)
							(mid -0.137521 0.162921)
							(end -0.1016 0.1778)
						)
						(arc
							(start 0.1016 0.1778)
							(mid 0.137521 0.162921)
							(end 0.1524 0.127)
						)
					)
					(width 0)
					(fill yes)
				)
			)
		)
	)
	(footprint ""
		(layer "F.Cu")
		(at 20.701 -256.286 180)
		(property "Reference" "Q189"
			(at 0 0 180)
			(layer "F.SilkS")
			(hide yes)
			(effects
				(font
					(size 1.27 1.27)
				)
			)
		)
		(property "Value" "AO4406AL-GP"
			(at -3.707384 -1.5367 180)
			(unlocked yes)
			(layer "F.Fab")
			(hide yes)
			(effects
				(font
					(size 1.016 1.016)
					(thickness 0.1524)
				)
			)
		)
		(property "Device Type" "SOIC8H69"
			(at -3.707384 -3.0607 180)
			(unlocked yes)
			(layer "F.Fab")
			(hide yes)
			(effects
				(font
					(size 1.016 1.016)
					(thickness 0.1524)
				)
			)
		)
		(duplicate_pad_numbers_are_jumpers no)
		(fp_line
			(start 2.1336 1.4224)
			(end 2.1336 -1.4224)
			(stroke
				(width 0.1524)
				(type default)
			)
			(layer "F.SilkS")
		)
		(fp_line
			(start 2.1336 -1.4224)
			(end -2.7432 -1.4224)
			(stroke
				(width 0.1524)
				(type default)
			)
			(layer "F.SilkS")
		)
		(fp_line
			(start -2.1844 -0.0508)
			(end -2.7178 0.508)
			(stroke
				(width 0.1524)
				(type default)
			)
			(layer "F.SilkS")
		)
		(fp_line
			(start -2.6289 3.4417)
			(end -2.6289 1.4732)
			(stroke
				(width 0.381)
				(type default)
			)
			(layer "F.SilkS")
		)
		(fp_line
			(start -2.7178 -0.508)
			(end -2.1844 -0.0508)
			(stroke
				(width 0.1524)
				(type default)
			)
			(layer "F.SilkS")
		)
		(fp_line
			(start -2.7432 1.4224)
			(end 2.1336 1.4224)
			(stroke
				(width 0.1524)
				(type default)
			)
			(layer "F.SilkS")
		)
		(fp_line
			(start -2.7432 1.4224)
			(end -2.6416 1.4224)
			(stroke
				(width 0.1524)
				(type default)
			)
			(layer "F.SilkS")
		)
		(fp_line
			(start -2.7432 -1.4224)
			(end -2.7432 1.4224)
			(stroke
				(width 0.1524)
				(type default)
			)
			(layer "F.SilkS")
		)
		(fp_poly
			(pts
				(xy -2.2098 -1.4224) (xy -2.2098 1.4224) (xy 2.2098 1.4224) (xy 2.2098 -1.4224)
			)
			(stroke
				(width 0)
				(type default)
			)
			(fill yes)
			(layer "F.SilkS")
		)
		(fp_rect
			(start -2.450084 2.999994)
			(end 2.450084 -2.999994)
			(stroke
				(width 0)
				(type default)
			)
			(fill no)
			(layer "F.CrtYd")
		)
		(fp_poly
			(pts
				(xy -2.8194 3.6322) (xy -2.8194 -3.6322) (xy 2.8194 -3.6322) (xy 2.8194 1.18364) (xy 2.450084 1.18364)
				(xy 2.450084 -2.999994) (xy -2.450084 -2.999994) (xy -2.450084 2.999994) (xy 2.450084 2.999994)
				(xy 2.450084 1.18618) (xy 2.8194 1.18618) (xy 2.8194 3.6322)
			)
			(stroke
				(width 0)
				(type default)
			)
			(fill no)
			(layer "F.CrtYd")
		)
		(fp_rect
			(start -2.8194 3.6322)
			(end 2.8194 -3.6322)
			(stroke
				(width 0)
				(type default)
			)
			(fill no)
			(layer "F.Fab")
		)
		(pad "1" smd rect
			(at -1.905 2.54 180)
			(size 0.635 1.651)
			(layers "F.Cu" "F.Mask" "F.Paste")
			(net "P5V_HDD0")
		)
		(pad "2" smd rect
			(at -0.635 2.54 180)
			(size 0.635 1.651)
			(layers "F.Cu" "F.Mask" "F.Paste")
			(net "P5V_HDD0")
		)
		(pad "3" smd rect
			(at 0.635 2.54 180)
			(size 0.635 1.651)
			(layers "F.Cu" "F.Mask" "F.Paste")
			(net "P5V_HDD0")
		)
		(pad "4" smd rect
			(at 1.905 2.54 180)
			(size 0.635 1.651)
			(layers "F.Cu" "F.Mask" "F.Paste")
			(net "SW_HDD_P0")
		)
		(pad "5" smd rect
			(at 1.905 -2.54 180)
			(size 0.635 1.651)
			(layers "F.Cu" "F.Mask" "F.Paste")
			(net "P5V_B_1")
		)
		(pad "6" smd rect
			(at 0.635 -2.54 180)
			(size 0.635 1.651)
			(layers "F.Cu" "F.Mask" "F.Paste")
			(net "P5V_B_1")
		)
		(pad "7" smd rect
			(at -0.635 -2.54 180)
			(size 0.635 1.651)
			(layers "F.Cu" "F.Mask" "F.Paste")
			(net "P5V_B_1")
		)
		(pad "8" smd rect
			(at -1.905 -2.54 180)
			(size 0.635 1.651)
			(layers "F.Cu" "F.Mask" "F.Paste")
			(net "P5V_B_1")
		)
	)
	(footprint ""
		(layer "F.Cu")
		(at 424.434 -160.401 180)
		(property "Reference" "C309"
			(at 0 0 180)
			(layer "F.SilkS")
			(hide yes)
			(effects
				(font
					(size 1.27 1.27)
				)
			)
		)
		(property "Value" "SC1U25V3KX-GP"
			(at 0 -2.8194 180)
			(unlocked yes)
			(layer "F.Fab")
			(hide yes)
			(effects
				(font
					(size 1.016 1.016)
					(thickness 0.1524)
				)
			)
		)
		(property "Device Type" "C603H36"
			(at 0 -4.3434 180)
			(unlocked yes)
			(layer "F.Fab")
			(hide yes)
			(effects
				(font
					(size 1.016 1.016)
					(thickness 0.1524)
				)
			)
		)
		(duplicate_pad_numbers_are_jumpers no)
		(fp_line
			(start 0.508 0)
			(end -0.508 0)
			(stroke
				(width 0.2032)
				(type default)
			)
			(layer "F.SilkS")
		)
		(fp_rect
			(start -0.5842 1.3335)
			(end 0.5842 -1.3335)
			(stroke
				(width 0)
				(type default)
			)
			(fill no)
			(layer "F.CrtYd")
		)
		(fp_rect
			(start -0.5842 1.3335)
			(end 0.5842 -1.3335)
			(stroke
				(width 0)
				(type default)
			)
			(fill no)
			(layer "F.Fab")
		)
		(pad "1" smd custom
			(at 0 -0.762 180)
			(size 0.2159 0.2159)
			(layers "F.Cu" "F.Mask" "F.Paste")
			(net "P12V_HDD21")
			(options
				(clearance outline)
				(anchor circle)
			)
			(primitives
				(gr_poly
					(pts
						(arc
							(start -0.3302 -0.4318)
							(mid -0.402042 -0.402042)
							(end -0.4318 -0.3302)
						)
						(arc
							(start -0.4318 0.3302)
							(mid -0.402042 0.402042)
							(end -0.3302 0.4318)
						)
						(arc
							(start 0.3302 0.4318)
							(mid 0.402042 0.402042)
							(end 0.4318 0.3302)
						)
						(arc
							(start 0.4318 -0.3302)
							(mid 0.402042 -0.402042)
							(end 0.3302 -0.4318)
						)
					)
					(width 0)
					(fill yes)
				)
			)
		)
		(pad "2" smd custom
			(at 0 0.762 180)
			(size 0.2159 0.2159)
			(layers "F.Cu" "F.Mask" "F.Paste")
			(net "GND")
			(options
				(clearance outline)
				(anchor circle)
			)
			(primitives
				(gr_poly
					(pts
						(arc
							(start -0.3302 -0.4318)
							(mid -0.402042 -0.402042)
							(end -0.4318 -0.3302)
						)
						(arc
							(start -0.4318 0.3302)
							(mid -0.402042 0.402042)
							(end -0.3302 0.4318)
						)
						(arc
							(start 0.3302 0.4318)
							(mid 0.402042 0.402042)
							(end 0.4318 0.3302)
						)
						(arc
							(start 0.4318 -0.3302)
							(mid 0.402042 -0.402042)
							(end 0.3302 -0.4318)
						)
					)
					(width 0)
					(fill yes)
				)
			)
		)
	)
	(footprint ""
		(layer "F.Cu")
		(at 301.371 -226.7204 -90)
		(property "Reference" "R7"
			(at 0 0 270)
			(layer "F.SilkS")
			(hide yes)
			(effects
				(font
					(size 1.27 1.27)
				)
			)
		)
		(property "Value" "10KR2F-2-GP"
			(at 0.064008 -3.993896 270)
			(unlocked yes)
			(layer "F.Fab")
			(hide yes)
			(effects
				(font
					(size 1.016 1.016)
					(thickness 0.1524)
				)
			)
		)
		(property "Device Type" "R402H16"
			(at 0.064008 -5.517896 270)
			(unlocked yes)
			(layer "F.Fab")
			(hide yes)
			(effects
				(font
					(size 1.016 1.016)
					(thickness 0.1524)
				)
			)
		)
		(duplicate_pad_numbers_are_jumpers no)
		(fp_line
			(start -0.508 -0.9398)
			(end -0.508 0.9398)
			(stroke
				(width 0.1524)
				(type default)
			)
			(layer "F.SilkS")
		)
		(fp_line
			(start 0.508 -0.9398)
			(end -0.508 -0.9398)
			(stroke
				(width 0.1524)
				(type default)
			)
			(layer "F.SilkS")
		)
		(fp_rect
			(start -0.508 0.9398)
			(end 0.508 -0.9398)
			(stroke
				(width 0)
				(type default)
			)
			(fill no)
			(layer "F.CrtYd")
		)
		(fp_rect
			(start -0.508 0.9398)
			(end 0.508 -0.9398)
			(stroke
				(width 0)
				(type default)
			)
			(fill no)
			(layer "F.Fab")
		)
		(pad "1" smd custom
			(at 0 -0.4445 270)
			(size 0.1397 0.1397)
			(layers "F.Cu" "F.Mask" "F.Paste")
			(net "P3V3_STBY_B")
			(options
				(clearance outline)
				(anchor circle)
			)
			(primitives
				(gr_poly
					(pts
						(arc
							(start -0.1778 -0.2794)
							(mid -0.249642 -0.249642)
							(end -0.2794 -0.1778)
						)
						(arc
							(start -0.2794 0.1778)
							(mid -0.249642 0.249642)
							(end -0.1778 0.2794)
						)
						(arc
							(start 0.1778 0.2794)
							(mid 0.249642 0.249642)
							(end 0.2794 0.1778)
						)
						(arc
							(start 0.2794 -0.1778)
							(mid 0.249642 -0.249642)
							(end 0.1778 -0.2794)
						)
					)
					(width 0)
					(fill yes)
				)
			)
		)
		(pad "2" smd custom
			(at 0 0.4445 270)
			(size 0.1397 0.1397)
			(layers "F.Cu" "F.Mask" "F.Paste")
			(net "SCC_B_TYPE_3")
			(options
				(clearance outline)
				(anchor circle)
			)
			(primitives
				(gr_poly
					(pts
						(arc
							(start -0.1778 -0.2794)
							(mid -0.249642 -0.249642)
							(end -0.2794 -0.1778)
						)
						(arc
							(start -0.2794 0.1778)
							(mid -0.249642 0.249642)
							(end -0.1778 0.2794)
						)
						(arc
							(start 0.1778 0.2794)
							(mid 0.249642 0.249642)
							(end 0.2794 0.1778)
						)
						(arc
							(start 0.2794 -0.1778)
							(mid 0.249642 -0.249642)
							(end 0.1778 -0.2794)
						)
					)
					(width 0)
					(fill yes)
				)
			)
		)
	)
)
